FILE_TYPE = CONNECTIVITY;
{Allegro Design Entry HDL 16.6-p007 (v16-6-112F) 10/10/2012}
"PAGE_NUMBER" = 183;
0"NC";
1"P3V3_STBY\g";
2"FM_UART_ALERT_N";
%"P3V3_STBY"
"1","(3150,-150)","0","mstr_symbols","I2";
;
SIZE"1B"
CDS_LIB"mstr_symbols"
BODY_TYPE"PLUMBING"
VOLTAGE"3.3V"
HDL_POWER"P3V3_STBY";
"G\NAC"1;
%"RES"
"2","(3150,-400)","0","mstr_discrete","I3";
;
TOLERANCE"1%"
WATTAGE"1/16W"
MATERIAL"CHIP"
PACK_TYPE"0402"
VALUE"4.75K"
LOCATION"R9F55"
PART_NUMBER"G21796-072"
CDS_LIB"mstr_discrete"
ROOM"LBG"
BOM_COST"LBG_UART"
CDS_LOCATION"R9F55"
SEC"1"
SEC_TYPE"0402"
CDS_SEC"1";
"A"
$PN"1"1;
"B"
$PN"2"2;
END.
